# T6G (Grand Teton) — schematic parts with pin connectivity, parts 2597–2597 of 8303; source: Cadence DE-HDL packaged netlist (pstxprt.dat, pstxnet.dat, pstchip.dat)

J15  SCONN288_DDR506112002KQ  IO  pkg DDR288S_1-1VXC  page 87
  1  VIN_BULK0  POWER  = P12V_MEM_CPU0
  2  RFU0  TRI  = NC
  3  VIN_MGMT  POWER  = P3V3_AUX
  4  HSCL  IN  = I3C_SPD_DDRB_CPU0_SCL
  5  HSDA  BI  = I3C_SPD_DDRB_CPU0_SDA
  6  VSS0  POWER  = GND
  7  DQ0_A  BI  = M_B_CPU0_SA_DQ<0>
  8  VSS1  POWER  = GND
  9  DQ1_A  BI  = M_B_CPU0_SA_DQ<1>
  10  VSS2  POWER  = GND
  11  DQS0_A_T  BI  = M_B_CPU0_SA_DQS_DP<0>
  12  DQS0_A_C  BI  = M_B_CPU0_SA_DQS_DN<0>
  13  VSS3  POWER  = GND
  14  DQ4_A  BI  = M_B_CPU0_SA_DQ<4>
  15  VSS4  POWER  = GND
  16  DQ5_A  BI  = M_B_CPU0_SA_DQ<5>
  17  VSS5  POWER  = GND
  18  DQ8_A  BI  = M_B_CPU0_SA_DQ<8>
  19  VSS6  POWER  = GND
  20  DQ9_A  BI  = M_B_CPU0_SA_DQ<9>
  21  VSS7  POWER  = GND
  22  DQS1_A_T  BI  = M_B_CPU0_SA_DQS_DP<1>
  23  DQS1_A_C  BI  = M_B_CPU0_SA_DQS_DN<1>
  24  VSS8  POWER  = GND
  25  DQ12_A  BI  = M_B_CPU0_SA_DQ<12>
  26  VSS9  POWER  = GND
  27  DQ13_A  BI  = M_B_CPU0_SA_DQ<13>
  28  VSS10  POWER  = GND
  29  DQ16_A  BI  = M_B_CPU0_SA_DQ<16>
  30  VSS11  POWER  = GND
  31  DQ17_A  BI  = M_B_CPU0_SA_DQ<17>
  32  VSS12  POWER  = GND
  33  DQS2_A_T  BI  = M_B_CPU0_SA_DQS_DP<2>
  34  DQS2_A_C  BI  = M_B_CPU0_SA_DQS_DN<2>
  35  VSS13  POWER  = GND
  36  DQ20_A  BI  = M_B_CPU0_SA_DQ<20>
  37  VSS14  POWER  = GND
  38  DQ21_A  BI  = M_B_CPU0_SA_DQ<21>
  39  VSS15  POWER  = GND
  40  DQ24_A  BI  = M_B_CPU0_SA_DQ<24>
  41  VSS16  POWER  = GND
  42  DQ25_A  BI  = M_B_CPU0_SA_DQ<25>
  43  VSS17  POWER  = GND
  44  DQS3_A_T  BI  = M_B_CPU0_SA_DQS_DP<3>
  45  DQS3_A_C  BI  = M_B_CPU0_SA_DQS_DN<3>
  46  VSS18  POWER  = GND
  47  DQ28_A  BI  = M_B_CPU0_SA_DQ<28>
  48  VSS19  POWER  = GND
  49  DQ29_A  BI  = M_B_CPU0_SA_DQ<29>
  50  VSS20  POWER  = GND
  51  CB0_A  BI  = M_B_CPU0_SA_CB<0>
  52  VSS21  POWER  = GND
  53  CB1_A  BI  = M_B_CPU0_SA_CB<1>
  54  VSS22  POWER  = GND
  55  DQS4_A_T  BI  = M_B_CPU0_SA_DQS_DP<4>
  56  DQS4_A_C  BI  = M_B_CPU0_SA_DQS_DN<4>
  57  VSS23  POWER  = GND
  58  CB4_A  BI  = M_B_CPU0_SA_CB<4>
  59  VSS24  POWER  = GND
  60  CB5_A  BI  = M_B_CPU0_SA_CB<5>
  61  VSS25  POWER  = GND
  62  ALERT_N  OUT  = M_B_CPU0_ALERT_N
  63  VSS26  POWER  = GND
  64  CS0_A_N  IN  = M_B_CPU0_SA_CS_N<0>
  65  VSS27  POWER  = GND
  66  CA0_A  IN  = M_B_CPU0_SA_CA<0>
  67  VSS28  POWER  = GND
  68  CA2_A  IN  = M_B_CPU0_SA_CA<2>
  69  VSS29  POWER  = GND
  70  CA4_A  IN  = M_B_CPU0_SA_CA<4>
  71  VSS30  POWER  = GND
  72  CA6_A  IN  = M_B_CPU0_SA_CA<6>
  73  VSS31  POWER  = GND
  74  PAR_A  IN  = M_B_CPU0_SA_PAR
  75  VSS32  POWER  = GND
  76  CA0_B  IN  = M_B_CPU0_SB_CA<0>
  77  VSS33  POWER  = GND
  78  CA2_B  IN  = M_B_CPU0_SB_CA<2>
  79  VSS34  POWER  = GND
  80  CA4_B  IN  = M_B_CPU0_SB_CA<4>
  81  VSS35  POWER  = GND
  82  CA6_B  IN  = M_B_CPU0_SB_CA<6>
  83  VSS36  POWER  = GND
  84  CS0_B_N  IN  = M_B_CPU0_SB_CS_N<0>
  85  VSS37  POWER  = GND
  86  \lbd||rsp_a_n\  OUT  = M_B_CPU0_SA_RSP<0>
  87  \lbs||rsp_b_n\  OUT  = M_B_CPU0_SB_RSP<0>
  88  VSS38  POWER  = GND
  89  CB4_B  BI  = M_B_CPU0_SB_CB<4>
  90  VSS39  POWER  = GND
  91  CB5_B  BI  = M_B_CPU0_SB_CB<5>
  92  VSS40  POWER  = GND
  93  \dqs9_b_t||tdqs9_b_t||dbi4_b_n\  BI  = M_B_CPU0_SB_DQS_DP<9>
  94  \dqs9_b_c||tdqs9_b_c\  BI  = M_B_CPU0_SB_DQS_DN<9>
  95  VSS41  POWER  = GND
  96  CB0_B  BI  = M_B_CPU0_SB_CB<0>
  97  VSS42  POWER  = GND
  98  CB1_B  BI  = M_B_CPU0_SB_CB<1>
  99  VSS43  POWER  = GND
  100  DQ0_B  BI  = M_B_CPU0_SB_DQ<0>
  101  VSS44  POWER  = GND
  102  DQ1_B  BI  = M_B_CPU0_SB_DQ<1>
  103  VSS45  POWER  = GND
  104  DQS0_B_T  BI  = M_B_CPU0_SB_DQS_DP<0>
  105  DQS0_B_C  BI  = M_B_CPU0_SB_DQS_DN<0>
  106  VSS46  POWER  = GND
  107  DQ4_B  BI  = M_B_CPU0_SB_DQ<4>
  108  VSS47  POWER  = GND
  109  DQ5_B  BI  = M_B_CPU0_SB_DQ<5>
  110  VSS48  POWER  = GND
  111  DQ8_B  BI  = M_B_CPU0_SB_DQ<8>
  112  VSS49  POWER  = GND
  113  DQ9_B  BI  = M_B_CPU0_SB_DQ<9>
  114  VSS50  POWER  = GND
  115  DQS1_B_T  BI  = M_B_CPU0_SB_DQS_DP<1>
  116  DQS1_B_C  BI  = M_B_CPU0_SB_DQS_DN<1>
  117  VSS51  POWER  = GND
  118  DQ12_B  BI  = M_B_CPU0_SB_DQ<12>
  119  VSS52  POWER  = GND
  120  DQ13_B  BI  = M_B_CPU0_SB_DQ<13>
  121  VSS53  POWER  = GND
  122  DQ16_B  BI  = M_B_CPU0_SB_DQ<16>
  123  VSS54  POWER  = GND
  124  DQ17_B  BI  = M_B_CPU0_SB_DQ<17>
  125  VSS55  POWER  = GND
  126  DQS2_B_T  BI  = M_B_CPU0_SB_DQS_DP<2>
  127  DQS2_B_C  BI  = M_B_CPU0_SB_DQS_DN<2>
  128  VSS56  POWER  = GND
  129  DQ20_B  BI  = M_B_CPU0_SB_DQ<20>
  130  VSS57  POWER  = GND
  131  DQ21_B  BI  = M_B_CPU0_SB_DQ<21>
  132  VSS58  POWER  = GND
  133  DQ24_B  BI  = M_B_CPU0_SB_DQ<24>
  134  VSS59  POWER  = GND
  135  DQ25_B  BI  = M_B_CPU0_SB_DQ<25>
  136  VSS60  POWER  = GND
  137  DQS3_B_T  BI  = M_B_CPU0_SB_DQS_DP<3>
  138  DQS3_B_C  BI  = M_B_CPU0_SB_DQS_DN<3>
  139  VSS61  POWER  = GND
  140  DQ28_B  BI  = M_B_CPU0_SB_DQ<28>
  141  VSS62  POWER  = GND
  142  DQ29_B  BI  = M_B_CPU0_SB_DQ<29>
  143  VSS63  POWER  = GND
  144  RFU1  TRI  = NC
  145  VIN_BULK1  POWER  = P12V_MEM_CPU0
  146  VIN_BULK2  POWER  = P12V_MEM_CPU0
  147  \pwr_good||fail_n\  BI  = PWRGD_CHB_CPU0_DIMM
  148  HAS  IN  = PD_CHB_CPU0_DIMM_SAA
  149  RFU2  TRI  = NC
  150  RFU3  TRI  = NC
  151  VSS64  POWER  = GND
  152  DQ2_A  BI  = M_B_CPU0_SA_DQ<2>
  153  VSS65  POWER  = GND
  154  DQ3_A  BI  = M_B_CPU0_SA_DQ<3>
  155  VSS66  POWER  = GND
  156  \dqs5_a_c||tdqs5_a_c||dqs5_a_t||tdqs5_a_t\  BI  = M_B_CPU0_SA_DQS_DN<5>
  157  \dqs5_a_t||tdqs5_a_t\  BI  = M_B_CPU0_SA_DQS_DP<5>
  158  VSS67  POWER  = GND
  159  DQ6_A  BI  = M_B_CPU0_SA_DQ<6>
  160  VSS68  POWER  = GND
  161  DQ7_A  BI  = M_B_CPU0_SA_DQ<7>
  162  VSS69  POWER  = GND
  163  DQ10_A  BI  = M_B_CPU0_SA_DQ<10>
  164  VSS70  POWER  = GND
  165  DQ11_A  BI  = M_B_CPU0_SA_DQ<11>
  166  VSS71  POWER  = GND
  167  \dqs6_a_c||tdqs6_a_c||dqs6_a_t||tdqs6_a_t\  BI  = M_B_CPU0_SA_DQS_DN<6>
  168  \dqs6_a_t||tdqs6_a_t\  BI  = M_B_CPU0_SA_DQS_DP<6>
  169  VSS72  POWER  = GND
  170  DQ14_A  BI  = M_B_CPU0_SA_DQ<14>
  171  VSS73  POWER  = GND
  172  DQ15_A  BI  = M_B_CPU0_SA_DQ<15>
  173  VSS74  POWER  = GND
  174  DQ18_A  BI  = M_B_CPU0_SA_DQ<18>
  175  VSS75  POWER  = GND
  176  DQ19_A  BI  = M_B_CPU0_SA_DQ<19>
  177  VSS76  POWER  = GND
  178  \dqs7_a_c||tdqs7_a_c\  BI  = M_B_CPU0_SA_DQS_DN<7>
  179  \dqs7_a_t||tdqs7_a_t\  BI  = M_B_CPU0_SA_DQS_DP<7>
  180  VSS77  POWER  = GND
  181  DQ22_A  BI  = M_B_CPU0_SA_DQ<22>
  182  VSS78  POWER  = GND
  183  DQ23_A  BI  = M_B_CPU0_SA_DQ<23>
  184  VSS79  POWER  = GND
  185  DQ26_A  BI  = M_B_CPU0_SA_DQ<26>
  186  VSS80  POWER  = GND
  187  DQ27_A  BI  = M_B_CPU0_SA_DQ<27>
  188  VSS81  POWER  = GND
  189  \dqs8_a_c||tdqs8_a_c\  BI  = M_B_CPU0_SA_DQS_DN<8>
  190  \dqs8_a_t||tdqs8_a_t\  BI  = M_B_CPU0_SA_DQS_DP<8>
  191  VSS82  POWER  = GND
  192  DQ30_A  BI  = M_B_CPU0_SA_DQ<30>
  193  VSS83  POWER  = GND
  194  DQ31_A  BI  = M_B_CPU0_SA_DQ<31>
  195  VSS84  POWER  = GND
  196  CB2_A  BI  = M_B_CPU0_SA_CB<2>
  197  VSS85  POWER  = GND
  198  CB3_A  BI  = M_B_CPU0_SA_CB<3>
  199  VSS86  POWER  = GND
  200  \dqs9_a_c||tdqs9_a_c\  BI  = M_B_CPU0_SA_DQS_DN<9>
  201  \dqs9_a_t||tdqs9_a_t\  BI  = M_B_CPU0_SA_DQS_DP<9>
  202  VSS87  POWER  = GND
  203  CB6_A  BI  = M_B_CPU0_SA_CB<6>
  204  VSS88  POWER  = GND
  205  CB7_A  BI  = M_B_CPU0_SA_CB<7>
  206  VSS89  POWER  = GND
  207  RESET_N  IN  = M_B_CPU0_RESET_N
  208  VSS90  POWER  = GND
  209  CS1_A_N  IN  = M_B_CPU0_SA_CS_N<1>
  210  VSS91  POWER  = GND
  211  CA1_A  IN  = M_B_CPU0_SA_CA<1>
  212  VSS92  POWER  = GND
  213  CA3_A  IN  = M_B_CPU0_SA_CA<3>
  214  VSS93  POWER  = GND
  215  CA5_A  IN  = M_B_CPU0_SA_CA<5>
  216  VSS94  POWER  = GND
  217  CK_T  IN  = M_B_CPU0_CLK_DP<0>
  218  CK_C  IN  = M_B_CPU0_CLK_DN<0>
  219  VSS95  POWER  = GND
  220  RFU4  TRI  = NC
  221  CA1_B  IN  = M_B_CPU0_SB_CA<1>
  222  VSS96  POWER  = GND
  223  CA3_B  IN  = M_B_CPU0_SB_CA<3>
  224  VSS97  POWER  = GND
  225  CA5_B  IN  = M_B_CPU0_SB_CA<5>
  226  VSS98  POWER  = GND
  227  PAR_B  IN  = M_B_CPU0_SB_PAR
  228  VSS99  POWER  = GND
  229  CS1_B_N  IN  = M_B_CPU0_SB_CS_N<1>
  230  VSS100  POWER  = GND
  231  RFU5  TRI  = NC
  232  RFU6  TRI  = NC
  233  VSS101  POWER  = GND
  234  CB6_B  BI  = M_B_CPU0_SB_CB<6>
  235  VSS102  POWER  = GND
  236  CB7_B  BI  = M_B_CPU0_SB_CB<7>
  237  VSS103  POWER  = GND
  238  DQS4_B_C  BI  = M_B_CPU0_SB_DQS_DN<4>
  239  DQS4_B_T  BI  = M_B_CPU0_SB_DQS_DP<4>
  240  VSS104  POWER  = GND
  241  CB2_B  BI  = M_B_CPU0_SB_CB<2>
  242  VSS105  POWER  = GND
  243  CB3_B  BI  = M_B_CPU0_SB_CB<3>
  244  VSS106  POWER  = GND
  245  DQ2_B  BI  = M_B_CPU0_SB_DQ<2>
  246  VSS107  POWER  = GND
  247  DQ3_B  BI  = M_B_CPU0_SB_DQ<3>
  248  VSS108  POWER  = GND
  249  \dqs5_b_c||tdqs5_b_c\  BI  = M_B_CPU0_SB_DQS_DN<5>
  250  \dqs5_b_t||tdqs5_b_t\  BI  = M_B_CPU0_SB_DQS_DP<5>
  251  VSS109  POWER  = GND
  252  DQ6_B  BI  = M_B_CPU0_SB_DQ<6>
  253  VSS110  POWER  = GND
  254  DQ7_B  BI  = M_B_CPU0_SB_DQ<7>
  255  VSS111  POWER  = GND
  256  DQ10_B  BI  = M_B_CPU0_SB_DQ<10>
  257  VSS112  POWER  = GND
  258  DQ11_B  BI  = M_B_CPU0_SB_DQ<11>
  259  VSS113  POWER  = GND
  260  \dqs6_b_c||tdqs6_b_c\  BI  = M_B_CPU0_SB_DQS_DN<6>
  261  \dqs6_b_t||tdqs6_b_t\  BI  = M_B_CPU0_SB_DQS_DP<6>
  262  VSS114  POWER  = GND
  263  DQ14_B  BI  = M_B_CPU0_SB_DQ<14>
  264  VSS115  POWER  = GND
  265  DQ15_B  BI  = M_B_CPU0_SB_DQ<15>
  266  VSS116  POWER  = GND
  267  DQ18_B  BI  = M_B_CPU0_SB_DQ<18>
  268  VSS117  POWER  = GND
  269  DQ19_B  BI  = M_B_CPU0_SB_DQ<19>
  270  VSS118  POWER  = GND
  271  \dqs7_b_c||tdqs7_b_c\  BI  = M_B_CPU0_SB_DQS_DN<7>
  272  \dqs7_b_t||tdqs7_b_t\  BI  = M_B_CPU0_SB_DQS_DP<7>
  273  VSS119  POWER  = GND
  274  DQ22_B  BI  = M_B_CPU0_SB_DQ<22>
  275  VSS120  POWER  = GND
  276  DQ23_B  BI  = M_B_CPU0_SB_DQ<23>
  277  VSS121  POWER  = GND
  278  DQ26_B  BI  = M_B_CPU0_SB_DQ<26>
  279  VSS122  POWER  = GND
  280  DQ27_B  BI  = M_B_CPU0_SB_DQ<27>
  281  VSS123  POWER  = GND
  282  \dqs8_b_c||tdqs8_b_c\  BI  = M_B_CPU0_SB_DQS_DN<8>
  283  \dqs8_b_t||tdqs8_b_t\  BI  = M_B_CPU0_SB_DQS_DP<8>
  284  VSS124  POWER  = GND
  285  DQ30_B  BI  = M_B_CPU0_SB_DQ<30>
  286  VSS125  POWER  = GND
  287  DQ31_B  BI  = M_B_CPU0_SB_DQ<31>
  288  VSS126  POWER  = GND
  G1  G1  POWER  = GND
  G2  G2  POWER  = GND
  G3  G3  POWER  = GND
